(kicad_pcb
	(version 20260206)
	(generator "pcbnew")
	(generator_version "10.0")
	(general
		(thickness 1.6)
		(legacy_teardrops no)
	)
	(paper "A4")
	(title_block
		(title "01162023_DA0F0TEBIF0_F0T_Expander_BD_F_brd_V02_OCP.brd")
		(comment 1 "Grand Teton / footprints 6078-6079 of 9728")
	)
	(layers
		(0 "F.Cu" signal "TOP")
		(4 "In1.Cu" signal "GND")
		(6 "In2.Cu" signal "VCC")
		(8 "In3.Cu" signal "VCC1")
		(10 "In4.Cu" signal "GND1")
		(12 "In5.Cu" signal "IN1")
		(14 "In6.Cu" signal "GND2")
		(16 "In7.Cu" signal "IN2")
		(18 "In8.Cu" signal "GND3")
		(20 "In9.Cu" signal "IN3")
		(22 "In10.Cu" signal "GND4")
		(24 "In11.Cu" signal "IN4")
		(26 "In12.Cu" signal "GND5")
		(28 "In13.Cu" signal "IN5")
		(30 "In14.Cu" signal "GND6")
		(32 "In15.Cu" signal "IN6")
		(34 "In16.Cu" signal "GND7")
		(2 "B.Cu" signal "BOTTOM")
		(9 "F.Adhes" user "F.Adhesive")
		(11 "B.Adhes" user "B.Adhesive")
		(13 "F.Paste" user "Package Geometry/Pastemask Top")
		(15 "B.Paste" user "Package Geometry/Pastemask Bottom")
		(5 "F.SilkS" user "Ref Des/Silkscreen Top")
		(7 "B.SilkS" user "Ref Des/Silkscreen Bottom")
		(1 "F.Mask" user "Board Geometry/Soldermask Top")
		(3 "B.Mask" user "Board Geometry/Soldermask Bottom")
		(17 "Dwgs.User" user "User.Drawings")
		(19 "Cmts.User" user "User.Comments")
		(21 "Eco1.User" user "User.Eco1")
		(23 "Eco2.User" user "User.Eco2")
		(25 "Edge.Cuts" user "Board Geometry/Outline")
		(27 "Margin" user)
		(31 "F.CrtYd" user "Package Geometry/Place Bound Top")
		(29 "B.CrtYd" user "Package Geometry/Place Bound Bottom")
		(35 "F.Fab" user "Ref Des/Assembly Top")
		(33 "B.Fab" user "Ref Des/Assembly Bottom")
	)
	(footprint ""
		(layer "F.Cu")
		(at 215.69807 -235.765086 -90)
		(property "Reference" "R6318"
			(at 0 0 270)
			(layer "F.SilkS")
			(hide yes)
			(effects
				(font
					(size 1.27 1.27)
				)
			)
		)
		(property "Value" ""
			(at 0 0 270)
			(layer "F.Fab")
			(effects
				(font
					(size 1.27 1.27)
				)
			)
		)
		(duplicate_pad_numbers_are_jumpers no)
		(fp_line
			(start -0.7874 0.4064)
			(end -0.7874 -0.4064)
			(stroke
				(width 0.1524)
				(type default)
			)
			(layer "F.SilkS")
		)
		(fp_line
			(start 0.7874 0.4064)
			(end -0.7874 0.4064)
			(stroke
				(width 0.1524)
				(type default)
			)
			(layer "F.SilkS")
		)
		(fp_line
			(start -0.7874 -0.4064)
			(end 0.7874 -0.4064)
			(stroke
				(width 0.1524)
				(type default)
			)
			(layer "F.SilkS")
		)
		(fp_line
			(start 0.7874 -0.4064)
			(end 0.7874 0.4064)
			(stroke
				(width 0.1524)
				(type default)
			)
			(layer "F.SilkS")
		)
		(fp_line
			(start -0.67945 0.3048)
			(end -0.67945 -0.305054)
			(stroke
				(width 0.1)
				(type default)
			)
			(layer "F.Fab")
		)
		(fp_line
			(start -0.12065 0.3048)
			(end -0.67945 0.3048)
			(stroke
				(width 0.1)
				(type default)
			)
			(layer "F.Fab")
		)
		(fp_line
			(start 0.120396 0.3048)
			(end 0.120396 0.2794)
			(stroke
				(width 0.1)
				(type default)
			)
			(layer "F.Fab")
		)
		(fp_line
			(start 0.67945 0.3048)
			(end 0.120396 0.3048)
			(stroke
				(width 0.1)
				(type default)
			)
			(layer "F.Fab")
		)
		(fp_line
			(start -0.12065 0.2794)
			(end -0.12065 0.3048)
			(stroke
				(width 0.1)
				(type default)
			)
			(layer "F.Fab")
		)
		(fp_line
			(start 0.120396 0.2794)
			(end -0.12065 0.2794)
			(stroke
				(width 0.1)
				(type default)
			)
			(layer "F.Fab")
		)
		(fp_line
			(start -0.12065 -0.2794)
			(end 0.12065 -0.2794)
			(stroke
				(width 0.1)
				(type default)
			)
			(layer "F.Fab")
		)
		(fp_line
			(start 0.12065 -0.2794)
			(end 0.12065 -0.3048)
			(stroke
				(width 0.1)
				(type default)
			)
			(layer "F.Fab")
		)
		(fp_line
			(start 0.12065 -0.3048)
			(end 0.67945 -0.3048)
			(stroke
				(width 0.1)
				(type default)
			)
			(layer "F.Fab")
		)
		(fp_line
			(start 0.67945 -0.3048)
			(end 0.67945 0.3048)
			(stroke
				(width 0.1)
				(type default)
			)
			(layer "F.Fab")
		)
		(fp_line
			(start -0.67945 -0.305054)
			(end -0.12065 -0.305054)
			(stroke
				(width 0.1)
				(type default)
			)
			(layer "F.Fab")
		)
		(fp_line
			(start -0.12065 -0.305054)
			(end -0.12065 -0.2794)
			(stroke
				(width 0.1)
				(type default)
			)
			(layer "F.Fab")
		)
		(pad "1" smd circle
			(at -0.40005 0 270)
			(size 0 0)
			(layers "F.Cu" "F.Mask" "F.Paste")
			(net "SMB_PEX_LS_SDA")
		)
		(pad "2" smd circle
			(at 0.40005 0 270)
			(size 0 0)
			(layers "F.Cu" "F.Mask" "F.Paste")
			(net "SMB_PEX_MUX_SDA")
		)
	)
	(footprint ""
		(layer "F.Cu")
		(at 78.267814 -54.067456)
		(property "Reference" "PR217"
			(at 0 0 0)
			(layer "F.SilkS")
			(hide yes)
			(effects
				(font
					(size 1.27 1.27)
				)
			)
		)
		(property "Value" ""
			(at 0 0 0)
			(layer "F.Fab")
			(effects
				(font
					(size 1.27 1.27)
				)
			)
		)
		(duplicate_pad_numbers_are_jumpers no)
		(fp_line
			(start -0.7874 -0.4064)
			(end 0.7874 -0.4064)
			(stroke
				(width 0.1524)
				(type default)
			)
			(layer "F.SilkS")
		)
		(fp_line
			(start -0.7874 0.4064)
			(end -0.7874 -0.4064)
			(stroke
				(width 0.1524)
				(type default)
			)
			(layer "F.SilkS")
		)
		(fp_line
			(start 0.7874 -0.4064)
			(end 0.7874 0.4064)
			(stroke
				(width 0.1524)
				(type default)
			)
			(layer "F.SilkS")
		)
		(fp_line
			(start 0.7874 0.4064)
			(end -0.7874 0.4064)
			(stroke
				(width 0.1524)
				(type default)
			)
			(layer "F.SilkS")
		)
		(fp_line
			(start -0.67945 -0.305054)
			(end -0.12065 -0.305054)
			(stroke
				(width 0.1)
				(type default)
			)
			(layer "F.Fab")
		)
		(fp_line
			(start -0.67945 0.3048)
			(end -0.67945 -0.305054)
			(stroke
				(width 0.1)
				(type default)
			)
			(layer "F.Fab")
		)
		(fp_line
			(start -0.12065 -0.305054)
			(end -0.12065 -0.2794)
			(stroke
				(width 0.1)
				(type default)
			)
			(layer "F.Fab")
		)
		(fp_line
			(start -0.12065 -0.2794)
			(end 0.12065 -0.2794)
			(stroke
				(width 0.1)
				(type default)
			)
			(layer "F.Fab")
		)
		(fp_line
			(start -0.12065 0.2794)
			(end -0.12065 0.3048)
			(stroke
				(width 0.1)
				(type default)
			)
			(layer "F.Fab")
		)
		(fp_line
			(start -0.12065 0.3048)
			(end -0.67945 0.3048)
			(stroke
				(width 0.1)
				(type default)
			)
			(layer "F.Fab")
		)
		(fp_line
			(start 0.120396 0.2794)
			(end -0.12065 0.2794)
			(stroke
				(width 0.1)
				(type default)
			)
			(layer "F.Fab")
		)
		(fp_line
			(start 0.120396 0.3048)
			(end 0.120396 0.2794)
			(stroke
				(width 0.1)
				(type default)
			)
			(layer "F.Fab")
		)
		(fp_line
			(start 0.12065 -0.3048)
			(end 0.67945 -0.3048)
			(stroke
				(width 0.1)
				(type default)
			)
			(layer "F.Fab")
		)
		(fp_line
			(start 0.12065 -0.2794)
			(end 0.12065 -0.3048)
			(stroke
				(width 0.1)
				(type default)
			)
			(layer "F.Fab")
		)
		(fp_line
			(start 0.67945 -0.3048)
			(end 0.67945 0.3048)
			(stroke
				(width 0.1)
				(type default)
			)
			(layer "F.Fab")
		)
		(fp_line
			(start 0.67945 0.3048)
			(end 0.120396 0.3048)
			(stroke
				(width 0.1)
				(type default)
			)
			(layer "F.Fab")
		)
		(pad "1" smd circle
			(at -0.40005 0)
			(size 0 0)
			(layers "F.Cu" "F.Mask" "F.Paste")
			(net "P12V_SSD2_OCP")
		)
		(pad "2" smd circle
			(at 0.40005 0)
			(size 0 0)
			(layers "F.Cu" "F.Mask" "F.Paste")
			(net "GND")
		)
	)
)
